(kicad_pcb
	(version 20260206)
	(generator "pcbnew")
	(generator_version "10.0")
	(general
		(thickness 1.6)
		(legacy_teardrops no)
	)
	(paper "A4")
	(title_block
		(title "01162023_DA0F0TEBIF0_F0T_Expander_BD_F_brd_V02_OCP.brd")
		(comment 1 "Grand Teton / footprints 5793-5800 of 9728")
	)
	(layers
		(0 "F.Cu" signal "TOP")
		(4 "In1.Cu" signal "GND")
		(6 "In2.Cu" signal "VCC")
		(8 "In3.Cu" signal "VCC1")
		(10 "In4.Cu" signal "GND1")
		(12 "In5.Cu" signal "IN1")
		(14 "In6.Cu" signal "GND2")
		(16 "In7.Cu" signal "IN2")
		(18 "In8.Cu" signal "GND3")
		(20 "In9.Cu" signal "IN3")
		(22 "In10.Cu" signal "GND4")
		(24 "In11.Cu" signal "IN4")
		(26 "In12.Cu" signal "GND5")
		(28 "In13.Cu" signal "IN5")
		(30 "In14.Cu" signal "GND6")
		(32 "In15.Cu" signal "IN6")
		(34 "In16.Cu" signal "GND7")
		(2 "B.Cu" signal "BOTTOM")
		(9 "F.Adhes" user "F.Adhesive")
		(11 "B.Adhes" user "B.Adhesive")
		(13 "F.Paste" user "Package Geometry/Pastemask Top")
		(15 "B.Paste" user "Package Geometry/Pastemask Bottom")
		(5 "F.SilkS" user "Ref Des/Silkscreen Top")
		(7 "B.SilkS" user "Ref Des/Silkscreen Bottom")
		(1 "F.Mask" user "Board Geometry/Soldermask Top")
		(3 "B.Mask" user "Board Geometry/Soldermask Bottom")
		(17 "Dwgs.User" user "User.Drawings")
		(19 "Cmts.User" user "User.Comments")
		(21 "Eco1.User" user "User.Eco1")
		(23 "Eco2.User" user "User.Eco2")
		(25 "Edge.Cuts" user "Board Geometry/Outline")
		(27 "Margin" user)
		(31 "F.CrtYd" user "Package Geometry/Place Bound Top")
		(29 "B.CrtYd" user "Package Geometry/Place Bound Bottom")
		(35 "F.Fab" user "Ref Des/Assembly Top")
		(33 "B.Fab" user "Ref Des/Assembly Bottom")
	)
	(footprint ""
		(layer "F.Cu")
		(at 58.995056 -102.798372 180)
		(property "Reference" "R70"
			(at 0 0 180)
			(layer "F.SilkS")
			(hide yes)
			(effects
				(font
					(size 1.27 1.27)
				)
			)
		)
		(property "Value" ""
			(at 0 0 180)
			(layer "F.Fab")
			(effects
				(font
					(size 1.27 1.27)
				)
			)
		)
		(duplicate_pad_numbers_are_jumpers no)
		(fp_line
			(start 0.7874 0.4064)
			(end -0.7874 0.4064)
			(stroke
				(width 0.1524)
				(type default)
			)
			(layer "F.SilkS")
		)
		(fp_line
			(start 0.7874 -0.4064)
			(end 0.7874 0.4064)
			(stroke
				(width 0.1524)
				(type default)
			)
			(layer "F.SilkS")
		)
		(fp_line
			(start -0.7874 0.4064)
			(end -0.7874 -0.4064)
			(stroke
				(width 0.1524)
				(type default)
			)
			(layer "F.SilkS")
		)
		(fp_line
			(start -0.7874 -0.4064)
			(end 0.7874 -0.4064)
			(stroke
				(width 0.1524)
				(type default)
			)
			(layer "F.SilkS")
		)
		(fp_line
			(start 0.67945 0.3048)
			(end 0.120396 0.3048)
			(stroke
				(width 0.1)
				(type default)
			)
			(layer "F.Fab")
		)
		(fp_line
			(start 0.67945 -0.3048)
			(end 0.67945 0.3048)
			(stroke
				(width 0.1)
				(type default)
			)
			(layer "F.Fab")
		)
		(fp_line
			(start 0.12065 -0.2794)
			(end 0.12065 -0.3048)
			(stroke
				(width 0.1)
				(type default)
			)
			(layer "F.Fab")
		)
		(fp_line
			(start 0.12065 -0.3048)
			(end 0.67945 -0.3048)
			(stroke
				(width 0.1)
				(type default)
			)
			(layer "F.Fab")
		)
		(fp_line
			(start 0.120396 0.3048)
			(end 0.120396 0.2794)
			(stroke
				(width 0.1)
				(type default)
			)
			(layer "F.Fab")
		)
		(fp_line
			(start 0.120396 0.2794)
			(end -0.12065 0.2794)
			(stroke
				(width 0.1)
				(type default)
			)
			(layer "F.Fab")
		)
		(fp_line
			(start -0.12065 0.3048)
			(end -0.67945 0.3048)
			(stroke
				(width 0.1)
				(type default)
			)
			(layer "F.Fab")
		)
		(fp_line
			(start -0.12065 0.2794)
			(end -0.12065 0.3048)
			(stroke
				(width 0.1)
				(type default)
			)
			(layer "F.Fab")
		)
		(fp_line
			(start -0.12065 -0.2794)
			(end 0.12065 -0.2794)
			(stroke
				(width 0.1)
				(type default)
			)
			(layer "F.Fab")
		)
		(fp_line
			(start -0.12065 -0.305054)
			(end -0.12065 -0.2794)
			(stroke
				(width 0.1)
				(type default)
			)
			(layer "F.Fab")
		)
		(fp_line
			(start -0.67945 0.3048)
			(end -0.67945 -0.305054)
			(stroke
				(width 0.1)
				(type default)
			)
			(layer "F.Fab")
		)
		(fp_line
			(start -0.67945 -0.305054)
			(end -0.12065 -0.305054)
			(stroke
				(width 0.1)
				(type default)
			)
			(layer "F.Fab")
		)
		(pad "1" smd circle
			(at -0.40005 0 180)
			(size 0 0)
			(layers "F.Cu" "F.Mask" "F.Paste")
			(net "NCSI_NIC1_TXD1")
		)
		(pad "2" smd circle
			(at 0.40005 0 180)
			(size 0 0)
			(layers "F.Cu" "F.Mask" "F.Paste")
			(net "GND")
		)
	)
	(footprint ""
		(layer "F.Cu")
		(at 352.920554 -90.645234 180)
		(property "Reference" "R1608"
			(at 0 0 180)
			(layer "F.SilkS")
			(hide yes)
			(effects
				(font
					(size 1.27 1.27)
				)
			)
		)
		(property "Value" ""
			(at 0 0 180)
			(layer "F.Fab")
			(effects
				(font
					(size 1.27 1.27)
				)
			)
		)
		(duplicate_pad_numbers_are_jumpers no)
		(fp_line
			(start 0.7874 0.4064)
			(end -0.7874 0.4064)
			(stroke
				(width 0.1524)
				(type default)
			)
			(layer "F.SilkS")
		)
		(fp_line
			(start 0.7874 -0.4064)
			(end 0.7874 0.4064)
			(stroke
				(width 0.1524)
				(type default)
			)
			(layer "F.SilkS")
		)
		(fp_line
			(start -0.7874 0.4064)
			(end -0.7874 -0.4064)
			(stroke
				(width 0.1524)
				(type default)
			)
			(layer "F.SilkS")
		)
		(fp_line
			(start -0.7874 -0.4064)
			(end 0.7874 -0.4064)
			(stroke
				(width 0.1524)
				(type default)
			)
			(layer "F.SilkS")
		)
		(fp_line
			(start 0.67945 0.3048)
			(end 0.120396 0.3048)
			(stroke
				(width 0.1)
				(type default)
			)
			(layer "F.Fab")
		)
		(fp_line
			(start 0.67945 -0.3048)
			(end 0.67945 0.3048)
			(stroke
				(width 0.1)
				(type default)
			)
			(layer "F.Fab")
		)
		(fp_line
			(start 0.12065 -0.2794)
			(end 0.12065 -0.3048)
			(stroke
				(width 0.1)
				(type default)
			)
			(layer "F.Fab")
		)
		(fp_line
			(start 0.12065 -0.3048)
			(end 0.67945 -0.3048)
			(stroke
				(width 0.1)
				(type default)
			)
			(layer "F.Fab")
		)
		(fp_line
			(start 0.120396 0.3048)
			(end 0.120396 0.2794)
			(stroke
				(width 0.1)
				(type default)
			)
			(layer "F.Fab")
		)
		(fp_line
			(start 0.120396 0.2794)
			(end -0.12065 0.2794)
			(stroke
				(width 0.1)
				(type default)
			)
			(layer "F.Fab")
		)
		(fp_line
			(start -0.12065 0.3048)
			(end -0.67945 0.3048)
			(stroke
				(width 0.1)
				(type default)
			)
			(layer "F.Fab")
		)
		(fp_line
			(start -0.12065 0.2794)
			(end -0.12065 0.3048)
			(stroke
				(width 0.1)
				(type default)
			)
			(layer "F.Fab")
		)
		(fp_line
			(start -0.12065 -0.2794)
			(end 0.12065 -0.2794)
			(stroke
				(width 0.1)
				(type default)
			)
			(layer "F.Fab")
		)
		(fp_line
			(start -0.12065 -0.305054)
			(end -0.12065 -0.2794)
			(stroke
				(width 0.1)
				(type default)
			)
			(layer "F.Fab")
		)
		(fp_line
			(start -0.67945 0.3048)
			(end -0.67945 -0.305054)
			(stroke
				(width 0.1)
				(type default)
			)
			(layer "F.Fab")
		)
		(fp_line
			(start -0.67945 -0.305054)
			(end -0.12065 -0.305054)
			(stroke
				(width 0.1)
				(type default)
			)
			(layer "F.Fab")
		)
		(pad "1" smd circle
			(at -0.40005 0 180)
			(size 0 0)
			(layers "F.Cu" "F.Mask" "F.Paste")
			(net "BIC_I2C9_SSD_MUX1_A1")
		)
		(pad "2" smd circle
			(at 0.40005 0 180)
			(size 0 0)
			(layers "F.Cu" "F.Mask" "F.Paste")
			(net "GND")
		)
	)
	(footprint ""
		(layer "F.Cu")
		(at 63.525908 -165.670484 -90)
		(property "Reference" "R3305"
			(at 0 0 270)
			(layer "F.SilkS")
			(hide yes)
			(effects
				(font
					(size 1.27 1.27)
				)
			)
		)
		(property "Value" ""
			(at 0 0 270)
			(layer "F.Fab")
			(effects
				(font
					(size 1.27 1.27)
				)
			)
		)
		(duplicate_pad_numbers_are_jumpers no)
		(fp_line
			(start -0.7874 0.4064)
			(end -0.7874 -0.4064)
			(stroke
				(width 0.1524)
				(type default)
			)
			(layer "F.SilkS")
		)
		(fp_line
			(start 0.7874 0.4064)
			(end -0.7874 0.4064)
			(stroke
				(width 0.1524)
				(type default)
			)
			(layer "F.SilkS")
		)
		(fp_line
			(start -0.7874 -0.4064)
			(end 0.7874 -0.4064)
			(stroke
				(width 0.1524)
				(type default)
			)
			(layer "F.SilkS")
		)
		(fp_line
			(start 0.7874 -0.4064)
			(end 0.7874 0.4064)
			(stroke
				(width 0.1524)
				(type default)
			)
			(layer "F.SilkS")
		)
		(fp_line
			(start -0.67945 0.3048)
			(end -0.67945 -0.305054)
			(stroke
				(width 0.1)
				(type default)
			)
			(layer "F.Fab")
		)
		(fp_line
			(start -0.12065 0.3048)
			(end -0.67945 0.3048)
			(stroke
				(width 0.1)
				(type default)
			)
			(layer "F.Fab")
		)
		(fp_line
			(start 0.120396 0.3048)
			(end 0.120396 0.2794)
			(stroke
				(width 0.1)
				(type default)
			)
			(layer "F.Fab")
		)
		(fp_line
			(start 0.67945 0.3048)
			(end 0.120396 0.3048)
			(stroke
				(width 0.1)
				(type default)
			)
			(layer "F.Fab")
		)
		(fp_line
			(start -0.12065 0.2794)
			(end -0.12065 0.3048)
			(stroke
				(width 0.1)
				(type default)
			)
			(layer "F.Fab")
		)
		(fp_line
			(start 0.120396 0.2794)
			(end -0.12065 0.2794)
			(stroke
				(width 0.1)
				(type default)
			)
			(layer "F.Fab")
		)
		(fp_line
			(start -0.12065 -0.2794)
			(end 0.12065 -0.2794)
			(stroke
				(width 0.1)
				(type default)
			)
			(layer "F.Fab")
		)
		(fp_line
			(start 0.12065 -0.2794)
			(end 0.12065 -0.3048)
			(stroke
				(width 0.1)
				(type default)
			)
			(layer "F.Fab")
		)
		(fp_line
			(start 0.12065 -0.3048)
			(end 0.67945 -0.3048)
			(stroke
				(width 0.1)
				(type default)
			)
			(layer "F.Fab")
		)
		(fp_line
			(start 0.67945 -0.3048)
			(end 0.67945 0.3048)
			(stroke
				(width 0.1)
				(type default)
			)
			(layer "F.Fab")
		)
		(fp_line
			(start -0.67945 -0.305054)
			(end -0.12065 -0.305054)
			(stroke
				(width 0.1)
				(type default)
			)
			(layer "F.Fab")
		)
		(fp_line
			(start -0.12065 -0.305054)
			(end -0.12065 -0.2794)
			(stroke
				(width 0.1)
				(type default)
			)
			(layer "F.Fab")
		)
		(pad "1" smd circle
			(at -0.40005 0 270)
			(size 0 0)
			(layers "F.Cu" "F.Mask" "F.Paste")
			(net "FM_SYS_THROTTLE_R")
		)
		(pad "2" smd circle
			(at 0.40005 0 270)
			(size 0 0)
			(layers "F.Cu" "F.Mask" "F.Paste")
			(net "FM_SYS_THROTTLE_NIC1")
		)
	)
	(footprint ""
		(layer "F.Cu")
		(at 112.751108 -350.098614 90)
		(property "Reference" "C357"
			(at 0 0 90)
			(layer "F.SilkS")
			(hide yes)
			(effects
				(font
					(size 1.27 1.27)
				)
			)
		)
		(property "Value" ""
			(at 0 0 90)
			(layer "F.Fab")
			(effects
				(font
					(size 1.27 1.27)
				)
			)
		)
		(duplicate_pad_numbers_are_jumpers no)
		(fp_line
			(start 0.299974 -0.150114)
			(end 0.299974 0.150114)
			(stroke
				(width 0.1)
				(type default)
			)
			(layer "F.Fab")
		)
		(fp_line
			(start -0.299974 -0.150114)
			(end 0.299974 -0.150114)
			(stroke
				(width 0.1)
				(type default)
			)
			(layer "F.Fab")
		)
		(fp_line
			(start 0.299974 0.150114)
			(end -0.299974 0.150114)
			(stroke
				(width 0.1)
				(type default)
			)
			(layer "F.Fab")
		)
		(fp_line
			(start -0.299974 0.150114)
			(end -0.299974 -0.150114)
			(stroke
				(width 0.1)
				(type default)
			)
			(layer "F.Fab")
		)
		(pad "1" smd rect
			(at -0.2667 0 90)
			(size 0.3048 0.381)
			(layers "F.Cu" "F.Mask" "F.Paste")
			(net "P5E_PEX1_STN6_TX_DN<103>")
		)
		(pad "2" smd rect
			(at 0.2667 0 90)
			(size 0.3048 0.381)
			(layers "F.Cu" "F.Mask" "F.Paste")
			(net "P5E_PEX1_STN6_TX_C_DN<103>")
		)
	)
	(footprint ""
		(layer "F.Cu")
		(at 335.752948 -80.607662 90)
		(property "Reference" "R1171"
			(at 0 0 90)
			(layer "F.SilkS")
			(hide yes)
			(effects
				(font
					(size 1.27 1.27)
				)
			)
		)
		(property "Value" ""
			(at 0 0 90)
			(layer "F.Fab")
			(effects
				(font
					(size 1.27 1.27)
				)
			)
		)
		(duplicate_pad_numbers_are_jumpers no)
		(fp_line
			(start 0.7874 0.4064)
			(end -0.7874 0.4064)
			(stroke
				(width 0.1524)
				(type default)
			)
			(layer "F.SilkS")
		)
		(fp_line
			(start -0.12065 -0.305054)
			(end -0.12065 -0.2794)
			(stroke
				(width 0.1)
				(type default)
			)
			(layer "F.Fab")
		)
		(fp_line
			(start -0.67945 -0.305054)
			(end -0.12065 -0.305054)
			(stroke
				(width 0.1)
				(type default)
			)
			(layer "F.Fab")
		)
		(fp_line
			(start 0.67945 -0.3048)
			(end 0.67945 0.3048)
			(stroke
				(width 0.1)
				(type default)
			)
			(layer "F.Fab")
		)
		(fp_line
			(start 0.12065 -0.3048)
			(end 0.67945 -0.3048)
			(stroke
				(width 0.1)
				(type default)
			)
			(layer "F.Fab")
		)
		(fp_line
			(start 0.12065 -0.2794)
			(end 0.12065 -0.3048)
			(stroke
				(width 0.1)
				(type default)
			)
			(layer "F.Fab")
		)
		(fp_line
			(start -0.12065 -0.2794)
			(end 0.12065 -0.2794)
			(stroke
				(width 0.1)
				(type default)
			)
			(layer "F.Fab")
		)
		(fp_line
			(start 0.120396 0.2794)
			(end -0.12065 0.2794)
			(stroke
				(width 0.1)
				(type default)
			)
			(layer "F.Fab")
		)
		(fp_line
			(start -0.12065 0.2794)
			(end -0.12065 0.3048)
			(stroke
				(width 0.1)
				(type default)
			)
			(layer "F.Fab")
		)
		(fp_line
			(start 0.67945 0.3048)
			(end 0.120396 0.3048)
			(stroke
				(width 0.1)
				(type default)
			)
			(layer "F.Fab")
		)
		(fp_line
			(start 0.120396 0.3048)
			(end 0.120396 0.2794)
			(stroke
				(width 0.1)
				(type default)
			)
			(layer "F.Fab")
		)
		(fp_line
			(start -0.12065 0.3048)
			(end -0.67945 0.3048)
			(stroke
				(width 0.1)
				(type default)
			)
			(layer "F.Fab")
		)
		(fp_line
			(start -0.67945 0.3048)
			(end -0.67945 -0.305054)
			(stroke
				(width 0.1)
				(type default)
			)
			(layer "F.Fab")
		)
		(pad "1" smd circle
			(at -0.40005 0 90)
			(size 0 0)
			(layers "F.Cu" "F.Mask" "F.Paste")
			(net "CLK_100M_DB800ZL_SSD8_R_DN")
		)
		(pad "2" smd circle
			(at 0.40005 0 90)
			(size 0 0)
			(layers "F.Cu" "F.Mask" "F.Paste")
			(net "CLK_100M_DB800ZL_SSD8_DN")
		)
	)
	(footprint ""
		(layer "F.Cu")
		(at 74.697082 -343.952322 90)
		(property "Reference" "C140"
			(at 0 0 90)
			(layer "F.SilkS")
			(hide yes)
			(effects
				(font
					(size 1.27 1.27)
				)
			)
		)
		(property "Value" ""
			(at 0 0 90)
			(layer "F.Fab")
			(effects
				(font
					(size 1.27 1.27)
				)
			)
		)
		(duplicate_pad_numbers_are_jumpers no)
		(fp_line
			(start 0.299974 -0.150114)
			(end 0.299974 0.150114)
			(stroke
				(width 0.1)
				(type default)
			)
			(layer "F.Fab")
		)
		(fp_line
			(start -0.299974 -0.150114)
			(end 0.299974 -0.150114)
			(stroke
				(width 0.1)
				(type default)
			)
			(layer "F.Fab")
		)
		(fp_line
			(start 0.299974 0.150114)
			(end -0.299974 0.150114)
			(stroke
				(width 0.1)
				(type default)
			)
			(layer "F.Fab")
		)
		(fp_line
			(start -0.299974 0.150114)
			(end -0.299974 -0.150114)
			(stroke
				(width 0.1)
				(type default)
			)
			(layer "F.Fab")
		)
		(pad "1" smd rect
			(at -0.2667 0 90)
			(size 0.3048 0.381)
			(layers "F.Cu" "F.Mask" "F.Paste")
			(net "P5E_PEX0_STN6_TX_DN<106>")
		)
		(pad "2" smd rect
			(at 0.2667 0 90)
			(size 0.3048 0.381)
			(layers "F.Cu" "F.Mask" "F.Paste")
			(net "P5E_PEX0_STN6_TX_C_DN<106>")
		)
	)
	(footprint ""
		(layer "F.Cu")
		(at 258.538218 -378.393706 -90)
		(property "Reference" "PR6603"
			(at 0 0 270)
			(layer "F.SilkS")
			(hide yes)
			(effects
				(font
					(size 1.27 1.27)
				)
			)
		)
		(property "Value" ""
			(at 0 0 270)
			(layer "F.Fab")
			(effects
				(font
					(size 1.27 1.27)
				)
			)
		)
		(duplicate_pad_numbers_are_jumpers no)
		(fp_line
			(start -3.9878 3.5814)
			(end -3.9878 -3.5814)
			(stroke
				(width 0.1524)
				(type default)
			)
			(layer "F.SilkS")
		)
		(fp_line
			(start 3.9878 3.5814)
			(end -3.9878 3.5814)
			(stroke
				(width 0.1524)
				(type default)
			)
			(layer "F.SilkS")
		)
		(fp_line
			(start -3.9878 -3.5814)
			(end 3.9878 -3.5814)
			(stroke
				(width 0.1524)
				(type default)
			)
			(layer "F.SilkS")
		)
		(fp_line
			(start 3.9878 -3.5814)
			(end 3.9878 3.5814)
			(stroke
				(width 0.1524)
				(type default)
			)
			(layer "F.SilkS")
		)
		(fp_line
			(start -3.5306 3.353054)
			(end -3.5306 -3.353054)
			(stroke
				(width 0.1)
				(type default)
			)
			(layer "F.Fab")
		)
		(fp_line
			(start 3.5306 3.353054)
			(end -3.5306 3.353054)
			(stroke
				(width 0.1)
				(type default)
			)
			(layer "F.Fab")
		)
		(fp_line
			(start -3.5306 -3.353054)
			(end 3.5306 -3.353054)
			(stroke
				(width 0.1)
				(type default)
			)
			(layer "F.Fab")
		)
		(fp_line
			(start 3.5306 -3.353054)
			(end 3.5306 3.353054)
			(stroke
				(width 0.1)
				(type default)
			)
			(layer "F.Fab")
		)
		(pad "1A" smd rect
			(at -2.249932 0 90)
			(size 3.2004 6.858)
			(layers "F.Cu" "F.Mask" "F.Paste")
			(net "P12V_STBY")
		)
		(pad "1B" smd rect
			(at -0.776732 0 270)
			(size 0.254 0.508)
			(layers "F.Cu" "F.Mask" "F.Paste")
			(net "P12V_HSC_SENSE2_R2_P")
		)
		(pad "2A" smd rect
			(at 2.249932 0 90)
			(size 3.2004 6.858)
			(layers "F.Cu" "F.Mask" "F.Paste")
			(net "P12V_STBY_R2")
		)
		(pad "2B" smd rect
			(at 0.776732 0 270)
			(size 0.254 0.508)
			(layers "F.Cu" "F.Mask" "F.Paste")
			(net "P12V_HSC_SENSE2_R2_N")
		)
	)
	(footprint ""
		(layer "F.Cu")
		(at 393.669266 -83.785202 180)
		(property "Reference" "R1772"
			(at 0 0 180)
			(layer "F.SilkS")
			(hide yes)
			(effects
				(font
					(size 1.27 1.27)
				)
			)
		)
		(property "Value" ""
			(at 0 0 180)
			(layer "F.Fab")
			(effects
				(font
					(size 1.27 1.27)
				)
			)
		)
		(duplicate_pad_numbers_are_jumpers no)
		(fp_line
			(start 0.7874 0.4064)
			(end -0.7874 0.4064)
			(stroke
				(width 0.1524)
				(type default)
			)
			(layer "F.SilkS")
		)
		(fp_line
			(start 0.7874 -0.4064)
			(end 0.7874 0.4064)
			(stroke
				(width 0.1524)
				(type default)
			)
			(layer "F.SilkS")
		)
		(fp_line
			(start -0.7874 0.4064)
			(end -0.7874 -0.4064)
			(stroke
				(width 0.1524)
				(type default)
			)
			(layer "F.SilkS")
		)
		(fp_line
			(start -0.7874 -0.4064)
			(end 0.7874 -0.4064)
			(stroke
				(width 0.1524)
				(type default)
			)
			(layer "F.SilkS")
		)
		(fp_line
			(start 0.67945 0.3048)
			(end 0.120396 0.3048)
			(stroke
				(width 0.1)
				(type default)
			)
			(layer "F.Fab")
		)
		(fp_line
			(start 0.67945 -0.3048)
			(end 0.67945 0.3048)
			(stroke
				(width 0.1)
				(type default)
			)
			(layer "F.Fab")
		)
		(fp_line
			(start 0.12065 -0.2794)
			(end 0.12065 -0.3048)
			(stroke
				(width 0.1)
				(type default)
			)
			(layer "F.Fab")
		)
		(fp_line
			(start 0.12065 -0.3048)
			(end 0.67945 -0.3048)
			(stroke
				(width 0.1)
				(type default)
			)
			(layer "F.Fab")
		)
		(fp_line
			(start 0.120396 0.3048)
			(end 0.120396 0.2794)
			(stroke
				(width 0.1)
				(type default)
			)
			(layer "F.Fab")
		)
		(fp_line
			(start 0.120396 0.2794)
			(end -0.12065 0.2794)
			(stroke
				(width 0.1)
				(type default)
			)
			(layer "F.Fab")
		)
		(fp_line
			(start -0.12065 0.3048)
			(end -0.67945 0.3048)
			(stroke
				(width 0.1)
				(type default)
			)
			(layer "F.Fab")
		)
		(fp_line
			(start -0.12065 0.2794)
			(end -0.12065 0.3048)
			(stroke
				(width 0.1)
				(type default)
			)
			(layer "F.Fab")
		)
		(fp_line
			(start -0.12065 -0.2794)
			(end 0.12065 -0.2794)
			(stroke
				(width 0.1)
				(type default)
			)
			(layer "F.Fab")
		)
		(fp_line
			(start -0.12065 -0.305054)
			(end -0.12065 -0.2794)
			(stroke
				(width 0.1)
				(type default)
			)
			(layer "F.Fab")
		)
		(fp_line
			(start -0.67945 0.3048)
			(end -0.67945 -0.305054)
			(stroke
				(width 0.1)
				(type default)
			)
			(layer "F.Fab")
		)
		(fp_line
			(start -0.67945 -0.305054)
			(end -0.12065 -0.305054)
			(stroke
				(width 0.1)
				(type default)
			)
			(layer "F.Fab")
		)
		(pad "1" smd circle
			(at -0.40005 0 180)
			(size 0 0)
			(layers "F.Cu" "F.Mask" "F.Paste")
			(net "SMB_BIC_I2C6_MUX_CLK_R_SCL")
		)
		(pad "2" smd circle
			(at 0.40005 0 180)
			(size 0 0)
			(layers "F.Cu" "F.Mask" "F.Paste")
			(net "SMB_BIC_I2C6_MUX_CLK_SCL")
		)
	)
)
